# T6G (Grand Teton) — schematic netlist excerpt (pin names and nets, part order shuffled) for the footprints in the layout excerpt that follows; sources: Cadence DE-HDL packaged netlist, KiCad conversion of 04192023_DAF0TMB3IC0_F0TG_MB_C_brd_V02_OCP.brd

R6791  Q_RES  1K 1% CHIP  pkg 0201LF  page 355 : A = U21_E2 ; B = GND
R8029  Q_RES  249 1% CHIP  pkg 0402LF  page 256 : A = LED_P12V_SCM_FAULT ; B = P3V3_AUX
C2148  Q_CAP  22UF 4V 20% X6S  pkg C0402  page 68 : A = PVDDCR_SOC_P0 ; B = GND

(kicad_pcb
	(version 20260206)
	(generator "pcbnew")
	(generator_version "10.0")
	(general
		(thickness 1.6)
		(legacy_teardrops no)
	)
	(paper "A4")
	(title_block
		(title "04192023_DAF0TMB3IC0_F0TG_MB_C_brd_V02_OCP.brd")
		(comment 1 "Grand Teton / footprints 2821-2823 of 8354")
	)
	(layers
		(0 "F.Cu" signal "TOP")
		(4 "In1.Cu" signal "GND")
		(6 "In2.Cu" signal "IN1")
		(8 "In3.Cu" signal "GND1")
		(10 "In4.Cu" signal "IN2")
		(12 "In5.Cu" signal "GND2")
		(14 "In6.Cu" signal "IN3")
		(16 "In7.Cu" signal "GND3")
		(18 "In8.Cu" signal "VCC")
		(20 "In9.Cu" signal "VCC1")
		(22 "In10.Cu" signal "GND4")
		(24 "In11.Cu" signal "IN4")
		(26 "In12.Cu" signal "GND5")
		(28 "In13.Cu" signal "IN5")
		(30 "In14.Cu" signal "GND6")
		(32 "In15.Cu" signal "IN6")
		(34 "In16.Cu" signal "GND7")
		(2 "B.Cu" signal "BOTTOM")
		(9 "F.Adhes" user "F.Adhesive")
		(11 "B.Adhes" user "B.Adhesive")
		(13 "F.Paste" user "Package Geometry/Pastemask Top")
		(15 "B.Paste" user "Package Geometry/Pastemask Bottom")
		(5 "F.SilkS" user "Ref Des/Silkscreen Top")
		(7 "B.SilkS" user "Ref Des/Silkscreen Bottom")
		(1 "F.Mask" user "Board Geometry/Soldermask Top")
		(3 "B.Mask" user "Board Geometry/Soldermask Bottom")
		(17 "Dwgs.User" user "User.Drawings")
		(19 "Cmts.User" user "User.Comments")
		(21 "Eco1.User" user "User.Eco1")
		(23 "Eco2.User" user "User.Eco2")
		(25 "Edge.Cuts" user "Board Geometry/Outline")
		(27 "Margin" user)
		(31 "F.CrtYd" user "Package Geometry/Place Bound Top")
		(29 "B.CrtYd" user "Package Geometry/Place Bound Bottom")
		(35 "F.Fab" user "Ref Des/Assembly Top")
		(33 "B.Fab" user "Ref Des/Assembly Bottom")
	)
	(footprint ""
		(layer "F.Cu")
		(at 361.316016 -256.012188 90)
		(property "Reference" "C2148"
			(at 0 0 90)
			(layer "F.SilkS")
			(hide yes)
			(effects
				(font
					(size 1.27 1.27)
				)
			)
		)
		(property "Value" ""
			(at 0 0 90)
			(layer "F.Fab")
			(effects
				(font
					(size 1.27 1.27)
				)
			)
		)
		(duplicate_pad_numbers_are_jumpers no)
		(fp_line
			(start 0.7874 -0.4064)
			(end 0.7874 0.4064)
			(stroke
				(width 0.1524)
				(type default)
			)
			(layer "F.SilkS")
		)
		(fp_line
			(start -0.7874 -0.4064)
			(end 0.7874 -0.4064)
			(stroke
				(width 0.1524)
				(type default)
			)
			(layer "F.SilkS")
		)
		(fp_line
			(start 0.7874 0.4064)
			(end -0.7874 0.4064)
			(stroke
				(width 0.1524)
				(type default)
			)
			(layer "F.SilkS")
		)
		(fp_line
			(start -0.7874 0.4064)
			(end -0.7874 -0.4064)
			(stroke
				(width 0.1524)
				(type default)
			)
			(layer "F.SilkS")
		)
		(fp_line
			(start -0.12065 -0.305054)
			(end -0.12065 -0.2794)
			(stroke
				(width 0.1)
				(type default)
			)
			(layer "F.Fab")
		)
		(fp_line
			(start -0.67945 -0.305054)
			(end -0.12065 -0.305054)
			(stroke
				(width 0.1)
				(type default)
			)
			(layer "F.Fab")
		)
		(fp_line
			(start 0.67945 -0.3048)
			(end 0.67945 0.3048)
			(stroke
				(width 0.1)
				(type default)
			)
			(layer "F.Fab")
		)
		(fp_line
			(start 0.12065 -0.3048)
			(end 0.67945 -0.3048)
			(stroke
				(width 0.1)
				(type default)
			)
			(layer "F.Fab")
		)
		(fp_line
			(start 0.12065 -0.2794)
			(end 0.12065 -0.3048)
			(stroke
				(width 0.1)
				(type default)
			)
			(layer "F.Fab")
		)
		(fp_line
			(start -0.12065 -0.2794)
			(end 0.12065 -0.2794)
			(stroke
				(width 0.1)
				(type default)
			)
			(layer "F.Fab")
		)
		(fp_line
			(start 0.120396 0.2794)
			(end -0.12065 0.2794)
			(stroke
				(width 0.1)
				(type default)
			)
			(layer "F.Fab")
		)
		(fp_line
			(start -0.12065 0.2794)
			(end -0.12065 0.3048)
			(stroke
				(width 0.1)
				(type default)
			)
			(layer "F.Fab")
		)
		(fp_line
			(start 0.67945 0.3048)
			(end 0.120396 0.3048)
			(stroke
				(width 0.1)
				(type default)
			)
			(layer "F.Fab")
		)
		(fp_line
			(start 0.120396 0.3048)
			(end 0.120396 0.2794)
			(stroke
				(width 0.1)
				(type default)
			)
			(layer "F.Fab")
		)
		(fp_line
			(start -0.12065 0.3048)
			(end -0.67945 0.3048)
			(stroke
				(width 0.1)
				(type default)
			)
			(layer "F.Fab")
		)
		(fp_line
			(start -0.67945 0.3048)
			(end -0.67945 -0.305054)
			(stroke
				(width 0.1)
				(type default)
			)
			(layer "F.Fab")
		)
		(pad "1" smd circle
			(at -0.40005 0 90)
			(size 0 0)
			(layers "F.Cu" "F.Mask" "F.Paste")
			(net "PVDDCR_SOC_P0")
		)
		(pad "2" smd circle
			(at 0.40005 0 90)
			(size 0 0)
			(layers "F.Cu" "F.Mask" "F.Paste")
			(net "GND")
		)
	)
	(footprint ""
		(layer "F.Cu")
		(at 169.230548 -429.022002 180)
		(property "Reference" "R6791"
			(at 0 0 180)
			(layer "F.SilkS")
			(hide yes)
			(effects
				(font
					(size 1.27 1.27)
				)
			)
		)
		(property "Value" ""
			(at 0 0 180)
			(layer "F.Fab")
			(effects
				(font
					(size 1.27 1.27)
				)
			)
		)
		(duplicate_pad_numbers_are_jumpers no)
		(fp_line
			(start 0.32512 0.175006)
			(end -0.32512 0.175006)
			(stroke
				(width 0.1)
				(type default)
			)
			(layer "F.Fab")
		)
		(fp_line
			(start 0.32512 -0.175006)
			(end 0.32512 0.175006)
			(stroke
				(width 0.1)
				(type default)
			)
			(layer "F.Fab")
		)
		(fp_line
			(start -0.32512 0.175006)
			(end -0.32512 -0.175006)
			(stroke
				(width 0.1)
				(type default)
			)
			(layer "F.Fab")
		)
		(fp_line
			(start -0.32512 -0.175006)
			(end 0.32512 -0.175006)
			(stroke
				(width 0.1)
				(type default)
			)
			(layer "F.Fab")
		)
		(pad "1" smd rect
			(at -0.2667 0 180)
			(size 0.3048 0.381)
			(layers "F.Cu" "F.Mask" "F.Paste")
			(net "U21_E2")
		)
		(pad "2" smd rect
			(at 0.2667 0)
			(size 0.3048 0.381)
			(layers "F.Cu" "F.Mask" "F.Paste")
			(net "GND")
		)
	)
	(footprint ""
		(layer "F.Cu")
		(at 193.294 -54.356 90)
		(property "Reference" "R8029"
			(at 0 0 90)
			(layer "F.SilkS")
			(hide yes)
			(effects
				(font
					(size 1.27 1.27)
				)
			)
		)
		(property "Value" ""
			(at 0 0 90)
			(layer "F.Fab")
			(effects
				(font
					(size 1.27 1.27)
				)
			)
		)
		(duplicate_pad_numbers_are_jumpers no)
		(fp_line
			(start 0.7874 -0.4064)
			(end 0.7874 0.4064)
			(stroke
				(width 0.1524)
				(type default)
			)
			(layer "F.SilkS")
		)
		(fp_line
			(start -0.7874 -0.4064)
			(end 0.7874 -0.4064)
			(stroke
				(width 0.1524)
				(type default)
			)
			(layer "F.SilkS")
		)
		(fp_line
			(start 0.7874 0.4064)
			(end -0.7874 0.4064)
			(stroke
				(width 0.1524)
				(type default)
			)
			(layer "F.SilkS")
		)
		(fp_line
			(start -0.7874 0.4064)
			(end -0.7874 -0.4064)
			(stroke
				(width 0.1524)
				(type default)
			)
			(layer "F.SilkS")
		)
		(fp_line
			(start -0.12065 -0.305054)
			(end -0.12065 -0.2794)
			(stroke
				(width 0.1)
				(type default)
			)
			(layer "F.Fab")
		)
		(fp_line
			(start -0.67945 -0.305054)
			(end -0.12065 -0.305054)
			(stroke
				(width 0.1)
				(type default)
			)
			(layer "F.Fab")
		)
		(fp_line
			(start 0.67945 -0.3048)
			(end 0.67945 0.3048)
			(stroke
				(width 0.1)
				(type default)
			)
			(layer "F.Fab")
		)
		(fp_line
			(start 0.12065 -0.3048)
			(end 0.67945 -0.3048)
			(stroke
				(width 0.1)
				(type default)
			)
			(layer "F.Fab")
		)
		(fp_line
			(start 0.12065 -0.2794)
			(end 0.12065 -0.3048)
			(stroke
				(width 0.1)
				(type default)
			)
			(layer "F.Fab")
		)
		(fp_line
			(start -0.12065 -0.2794)
			(end 0.12065 -0.2794)
			(stroke
				(width 0.1)
				(type default)
			)
			(layer "F.Fab")
		)
		(fp_line
			(start 0.120396 0.2794)
			(end -0.12065 0.2794)
			(stroke
				(width 0.1)
				(type default)
			)
			(layer "F.Fab")
		)
		(fp_line
			(start -0.12065 0.2794)
			(end -0.12065 0.3048)
			(stroke
				(width 0.1)
				(type default)
			)
			(layer "F.Fab")
		)
		(fp_line
			(start 0.67945 0.3048)
			(end 0.120396 0.3048)
			(stroke
				(width 0.1)
				(type default)
			)
			(layer "F.Fab")
		)
		(fp_line
			(start 0.120396 0.3048)
			(end 0.120396 0.2794)
			(stroke
				(width 0.1)
				(type default)
			)
			(layer "F.Fab")
		)
		(fp_line
			(start -0.12065 0.3048)
			(end -0.67945 0.3048)
			(stroke
				(width 0.1)
				(type default)
			)
			(layer "F.Fab")
		)
		(fp_line
			(start -0.67945 0.3048)
			(end -0.67945 -0.305054)
			(stroke
				(width 0.1)
				(type default)
			)
			(layer "F.Fab")
		)
		(pad "1" smd circle
			(at -0.40005 0 90)
			(size 0 0)
			(layers "F.Cu" "F.Mask" "F.Paste")
			(net "LED_P12V_SCM_FAULT")
		)
		(pad "2" smd circle
			(at 0.40005 0 90)
			(size 0 0)
			(layers "F.Cu" "F.Mask" "F.Paste")
			(net "P3V3_AUX")
		)
	)
)
